# S9S_MB_2U (Grand Teton) — schematic netlist excerpt (pin names and nets, part order shuffled) for the footprints in the layout excerpt that follows; sources: Cadence DE-HDL packaged netlist, KiCad conversion of 03242023_DA0F0TMBIJ0_F0T_Motherboard_J_brd_V01_OCP.brd

C156  Q_CAP_DIFFBUS  DIFF BUS_0.22UF 6.3V 20% X6S  pkg C0201  page 178 : \1\ = DMI_CPU0_PCH_RX_C_DP<7> ; \2\ = DMI_CPU0_PCH_RX_DP<7>
R3900  Q_RES  49.9 1% CHIP  pkg 0402LF  page 107 : A = I3C_SPD_DDREFGH_CPU1_LVC1_SCL_1 ; B = I3C_SPD_DDREFGH_CPU1_LVC1_SCL

(kicad_pcb
	(version 20260206)
	(generator "pcbnew")
	(generator_version "10.0")
	(general
		(thickness 1.6)
		(legacy_teardrops no)
	)
	(paper "A4")
	(title_block
		(title "03242023_DA0F0TMBIJ0_F0T_Motherboard_J_brd_V01_OCP.brd")
		(comment 1 "Grand Teton / footprints 6034-6035 of 6105")
	)
	(layers
		(0 "F.Cu" signal "TOP")
		(4 "In1.Cu" signal "GND")
		(6 "In2.Cu" signal "IN1")
		(8 "In3.Cu" signal "GND1")
		(10 "In4.Cu" signal "IN2")
		(12 "In5.Cu" signal "GND2")
		(14 "In6.Cu" signal "IN3")
		(16 "In7.Cu" signal "GND3")
		(18 "In8.Cu" signal "VCC")
		(20 "In9.Cu" signal "VCC1")
		(22 "In10.Cu" signal "GND4")
		(24 "In11.Cu" signal "IN4")
		(26 "In12.Cu" signal "GND5")
		(28 "In13.Cu" signal "IN5")
		(30 "In14.Cu" signal "GND6")
		(32 "In15.Cu" signal "IN6")
		(34 "In16.Cu" signal "GND7")
		(2 "B.Cu" signal "BOTTOM")
		(9 "F.Adhes" user "F.Adhesive")
		(11 "B.Adhes" user "B.Adhesive")
		(13 "F.Paste" user "Package Geometry/Pastemask Top")
		(15 "B.Paste" user "Package Geometry/Pastemask Bottom")
		(5 "F.SilkS" user "Ref Des/Silkscreen Top")
		(7 "B.SilkS" user "Ref Des/Silkscreen Bottom")
		(1 "F.Mask" user "Board Geometry/Soldermask Top")
		(3 "B.Mask" user "Board Geometry/Soldermask Bottom")
		(17 "Dwgs.User" user "User.Drawings")
		(19 "Cmts.User" user "User.Comments")
		(21 "Eco1.User" user "User.Eco1")
		(23 "Eco2.User" user "User.Eco2")
		(25 "Edge.Cuts" user "Board Geometry/Outline")
		(27 "Margin" user)
		(31 "F.CrtYd" user "Package Geometry/Place Bound Top")
		(29 "B.CrtYd" user "Package Geometry/Place Bound Bottom")
		(35 "F.Fab" user "Ref Des/Assembly Top")
		(33 "B.Fab" user "Ref Des/Assembly Bottom")
	)
	(footprint ""
		(layer "B.Cu")
		(at 349.675704 -64.18072)
		(property "Reference" "C156"
			(at 0 0 0)
			(layer "B.SilkS")
			(hide yes)
			(effects
				(font
					(size 1.27 1.27)
				)
				(justify mirror)
			)
		)
		(property "Value" ""
			(at 0 0 0)
			(layer "B.Fab")
			(effects
				(font
					(size 1.27 1.27)
				)
				(justify mirror)
			)
		)
		(duplicate_pad_numbers_are_jumpers no)
		(fp_line
			(start -0.299974 -0.150114)
			(end -0.299974 0.150114)
			(stroke
				(width 0.1)
				(type default)
			)
			(layer "B.Fab")
		)
		(fp_line
			(start -0.299974 0.150114)
			(end 0.299974 0.150114)
			(stroke
				(width 0.1)
				(type default)
			)
			(layer "B.Fab")
		)
		(fp_line
			(start 0.299974 -0.150114)
			(end -0.299974 -0.150114)
			(stroke
				(width 0.1)
				(type default)
			)
			(layer "B.Fab")
		)
		(fp_line
			(start 0.299974 0.150114)
			(end 0.299974 -0.150114)
			(stroke
				(width 0.1)
				(type default)
			)
			(layer "B.Fab")
		)
		(pad "1" smd rect
			(at 0.2667 0 180)
			(size 0.3048 0.381)
			(layers "B.Cu" "B.Mask" "B.Paste")
			(net "DMI_CPU0_PCH_RX_C_DP<7>")
		)
		(pad "2" smd rect
			(at -0.2667 0 180)
			(size 0.3048 0.381)
			(layers "B.Cu" "B.Mask" "B.Paste")
			(net "DMI_CPU0_PCH_RX_DP<7>")
		)
	)
	(footprint ""
		(layer "B.Cu")
		(at 158.697168 -318.336422)
		(property "Reference" "R3900"
			(at 0 0 0)
			(layer "B.SilkS")
			(hide yes)
			(effects
				(font
					(size 1.27 1.27)
				)
				(justify mirror)
			)
		)
		(property "Value" ""
			(at 0 0 0)
			(layer "B.Fab")
			(effects
				(font
					(size 1.27 1.27)
				)
				(justify mirror)
			)
		)
		(duplicate_pad_numbers_are_jumpers no)
		(fp_line
			(start -0.7874 -0.4064)
			(end -0.7874 0.4064)
			(stroke
				(width 0.1524)
				(type default)
			)
			(layer "B.SilkS")
		)
		(fp_line
			(start -0.7874 0.4064)
			(end 0.7874 0.4064)
			(stroke
				(width 0.1524)
				(type default)
			)
			(layer "B.SilkS")
		)
		(fp_line
			(start 0.7874 -0.4064)
			(end -0.7874 -0.4064)
			(stroke
				(width 0.1524)
				(type default)
			)
			(layer "B.SilkS")
		)
		(fp_line
			(start 0.7874 0.4064)
			(end 0.7874 -0.4064)
			(stroke
				(width 0.1524)
				(type default)
			)
			(layer "B.SilkS")
		)
		(fp_line
			(start -0.67945 -0.3048)
			(end -0.67945 0.3048)
			(stroke
				(width 0.1)
				(type default)
			)
			(layer "B.Fab")
		)
		(fp_line
			(start -0.67945 0.3048)
			(end -0.120396 0.3048)
			(stroke
				(width 0.1)
				(type default)
			)
			(layer "B.Fab")
		)
		(fp_line
			(start -0.12065 -0.3048)
			(end -0.67945 -0.3048)
			(stroke
				(width 0.1)
				(type default)
			)
			(layer "B.Fab")
		)
		(fp_line
			(start -0.12065 -0.2794)
			(end -0.12065 -0.3048)
			(stroke
				(width 0.1)
				(type default)
			)
			(layer "B.Fab")
		)
		(fp_line
			(start -0.120396 0.2794)
			(end 0.12065 0.2794)
			(stroke
				(width 0.1)
				(type default)
			)
			(layer "B.Fab")
		)
		(fp_line
			(start -0.120396 0.3048)
			(end -0.120396 0.2794)
			(stroke
				(width 0.1)
				(type default)
			)
			(layer "B.Fab")
		)
		(fp_line
			(start 0.12065 -0.305054)
			(end 0.12065 -0.2794)
			(stroke
				(width 0.1)
				(type default)
			)
			(layer "B.Fab")
		)
		(fp_line
			(start 0.12065 -0.2794)
			(end -0.12065 -0.2794)
			(stroke
				(width 0.1)
				(type default)
			)
			(layer "B.Fab")
		)
		(fp_line
			(start 0.12065 0.2794)
			(end 0.12065 0.3048)
			(stroke
				(width 0.1)
				(type default)
			)
			(layer "B.Fab")
		)
		(fp_line
			(start 0.12065 0.3048)
			(end 0.67945 0.3048)
			(stroke
				(width 0.1)
				(type default)
			)
			(layer "B.Fab")
		)
		(fp_line
			(start 0.67945 -0.305054)
			(end 0.12065 -0.305054)
			(stroke
				(width 0.1)
				(type default)
			)
			(layer "B.Fab")
		)
		(fp_line
			(start 0.67945 0.3048)
			(end 0.67945 -0.305054)
			(stroke
				(width 0.1)
				(type default)
			)
			(layer "B.Fab")
		)
		(pad "1" smd circle
			(at 0.40005 0 180)
			(size 0 0)
			(layers "B.Cu" "B.Mask" "B.Paste")
			(net "I3C_SPD_DDREFGH_CPU1_LVC1_SCL_1")
		)
		(pad "2" smd circle
			(at -0.40005 0 180)
			(size 0 0)
			(layers "B.Cu" "B.Mask" "B.Paste")
			(net "I3C_SPD_DDREFGH_CPU1_LVC1_SCL")
		)
	)
)
